FILE_TYPE = CONNECTIVITY;
{Allegro Design Entry HDL 16.6-p007 (v16-6-112F) 10/10/2012}
"PAGE_NUMBER" = 151;
0"NC";
1"GND\g";
2"GND\g";
3"P1V2_AUX_BMC\g";
4"GND\g";
5"P3V3_STBY\g";
6"GND\g";
7"P1V2_AUX_BMC\g";
8"GND\g";
9"GND\g";
10"P3V3_STBY\g";
11"P3V3_STBY\g";
12"GND\g";
13"GND\g";
14"P1V2_AUX_BMC\g";
15"GND\g";
16"GND\g";
17"P1V2_AUX_BMC\g";
18"P1V2_AUX_BMC\g";
19"GND\g";
20"P1V2_AUX_BMC\g";
21"P2V5_AUX_BMC\g";
22"GND\g";
23"BMC_M_A3";
24"BMC_M_DQ11";
25"BMC_M_CKE";
26"BMC_M_RST_N";
27"RST_BMC_DDR3_R_N";
28"BMC_M_ODT";
29"BMC_M_RST_N";
30"BMC_M_A9";
31"BMC_M_A10";
32"BMC_M_A11";
33"BMC_M_A12";
34"BMC_M_A13";
35"BMC_M_MACT_N";
36"BMC_M_VREFCA";
37"BMC_ZQ";
38"BMC_M_CLK";
39"BMC_M_CLK_DN";
40"BMC_M_BA1";
41"BMC_M_BA0";
42"BMC_M_DM0";
43"BMC_M_DM1";
44"BMC_M_CLK_DP";
45"BMC_M_DQS0_DP";
46"BMC_M_DQS1_DP";
47"BMC_M_DQ6";
48"BMC_M_DQ4";
49"BMC_M_DQ2";
50"BMC_M_DQ0";
51"BMC_M_DQ15";
52"BMC_M_DQ10";
53"BMC_M_DQ9";
54"BMC_M_DQ8";
55"BMC_M_A4";
56"BMC_M_A5";
57"BMC_M_A6";
58"BMC_M_A7";
59"BMC_M_A8";
60"BMC_M_A2";
61"BMC_M_A1";
62"BMC_M_BA1";
63"BMC_M_WE_N";
64"BMC_M_CAS_N";
65"BMC_M_CS_N";
66"BMC_M_MALERT_N";
67"BMC_M_A0";
68"BMC_M_BG0";
69"BMC_M_BA0";
70"BMC_M_RAS_N";
71"BMC_M_CKE";
72"BMC_M_DQ12";
73"BMC_M_A4";
74"BMC_M_A3";
75"BMC_M_VREFCA";
76"BMC_M_CLK_DP";
77"BMC_M_DQ1";
78"BMC_M_DQ3";
79"BMC_M_DQ5";
80"BMC_M_DQ7";
81"BMC_M_DQS1_DN";
82"BMC_M_DQS0_DN";
83"BMC_M_DQ13";
84"BMC_M_DQ14";
85"BMC_M_PAR";
86"BMC_M_ODT";
87"BMC_M_MALERT_N";
88"BMC_M_PAR";
89"FM_HEARTBEAT_LED";
90"RST_BMC_DDR3_BUF_IN_N";
91"BMC_M_BG0";
92"BMC_M_CS_N";
93"BMC_M_RST_N";
94"BMC_M_RAS_N";
95"BMC_M_CAS_N";
96"BMC_M_WE_N";
97"BMC_M_A12";
98"BMC_M_A10";
99"BMC_M_A8";
100"BMC_M_A6";
101"BMC_M_A2";
102"BMC_M_A0";
103"BMC_M_A1";
104"BMC_M_A5";
105"BMC_M_A13";
106"BMC_M_A7";
107"BMC_M_A9";
108"BMC_M_CLK_DN";
109"BMC_M_MACT_N";
110"FM_BMC_HEARTBEAT_N";
111"FM_HEARTBEAT_LED_K";
112"BMC_M_A11";
113"FM_HEARTBEAT_LED_A";
%"RES"
"2","(950,-100)","0","mstr_discrete","I101";
;
CDS_SEC"1"
PACK_TYPE"0402"
MATERIAL"CHIP"
TOLERANCE"1.0%"
LOCATION"R25W117"
VALUE"240"
PART_NUMBER"G21796-294"
WATTAGE"1/16W"
BOM_COST"SM_MEM"
ROOM"BMC_MEMORY"
CDS_LIB"mstr_discrete"
CDS_LOCATION"R25W117"
SEC"1"
SEC_TYPE"0402";
"A"
$PN"1"37;
"B"
$PN"2"1;
%"GND"
"1","(950,-300)","0","mstr_symbols","I112";
;
HDL_POWER"GND"
BODY_TYPE"PLUMBING"
VOLTAGE"0.0V"
CDS_LIB"mstr_symbols"
SIZE"1B";
"A\NAC"1;
%"GND"
"1","(600,-300)","0","mstr_symbols","I118";
;
HDL_POWER"GND"
BODY_TYPE"PLUMBING"
SIZE"1B"
CDS_LIB"mstr_symbols"
VOLTAGE"0.0V";
"A\NAC"2;
%"SC1U16V3KX-2GP"
"1","(-2500,2100)","0","w_hdl","I120";
;
VALUE"SC1U16V3KX-2GP"
PACK_SIZE"0603"
TYPE"X5R"
RATED"16V"
LOCATION"C25W17"
TOLERANCE"10%"
ATTRIBUTE"1UF"
CDS_SEC"1"
$SEC"1"
CDS_LOCATION"C25W17"
PACK_TYPE"SMD-BCG"
PART_NUMBER"78.10521.5BL"
CDS_LMAN_SYM_OUTLINE"-50,25,50,-25"
CDS_LIB"w_hdl";
"2"
$PN"2"4;
"1"
$PN"1"3;
%"SC1U16V3KX-2GP"
"1","(-2925,2100)","0","w_hdl","I121";
;
RATED"16V"
VALUE"SC1U16V3KX-2GP"
ATTRIBUTE"1UF"
LOCATION"C25W18"
TOLERANCE"10%"
TYPE"X5R"
PACK_SIZE"0603"
PACK_TYPE"SMD-BCG"
PART_NUMBER"78.10521.5BL"
CDS_LIB"w_hdl"
CDS_LMAN_SYM_OUTLINE"-50,25,50,-25"
CDS_LOCATION"C25W18"
$SEC"1"
CDS_SEC"1";
"2"
$PN"2"4;
"1"
$PN"1"3;
%"W_VCC_CIRCLE"
"1","(-3225,2300)","0","w_power","I122";
;
HDL_POWER"P1V2_AUX_BMC"
BODY_TYPE"PLUMBING"
CDS_LMAN_SYM_OUTLINE"-100,100,100,-100"
CDS_LIB"w_power";
"VCC_CIRCLE \B"3;
%"CAP"
"1","(-3225,2100)","0","mstr_discrete","I123";
;
CDS_SEC"1"
VALUE"4.7UF"
VOLTAGE"6.3V"
LOCATION"C25W19"
PART_NUMBER"E15431-003"
PACK_TYPE"0603"
MATERIAL"X6S"
TOLERANCE"10%"
CDS_LIB"mstr_discrete"
CDS_LOCATION"C25W19"
SEC"1"
SEC_TYPE"0603";
"A"
$PN"1"3;
"B"
$PN"2"4;
%"GND"
"1","(-3225,1825)","0","mstr_symbols","I124";
;
HDL_POWER"GND"
BODY_TYPE"PLUMBING"
CDS_LIB"mstr_symbols"
SIZE"1B"
VOLTAGE"0.0V";
"A\NAC"4;
%"CAP"
"1","(325,1675)","1","mstr_discrete","I125";
;
PART_NUMBER"D97712-011"
PACK_TYPE"0402"
VALUE"1.0UF"
MATERIAL"X6S"
VOLTAGE"16V"
TOLERANCE"10%"
LOCATION"C25W1"
CDS_SEC"1"
$SEC"1"
CDS_LOCATION"C25W1"
ROOM"VDDQ_KLM_PWR_VR"
CDS_LIB"mstr_discrete";
"A"
$PN"1"17;
"B"
$PN"2"6;
%"P3V3_STBY"
"1","(-50,200)","0","mstr_symbols","I136";
;
HDL_POWER"P3V3_STBY"
BODY_TYPE"PLUMBING"
VOLTAGE"3.3V"
CDS_LIB"mstr_symbols"
SIZE"1B";
"G\NAC"5;
%"GND"
"1","(625,325)","0","mstr_symbols","I137";
;
HDL_POWER"GND"
BODY_TYPE"PLUMBING"
CDS_LIB"mstr_symbols"
SIZE"1B"
VOLTAGE"0.0V";
"A\NAC"6;
%"RES"
"1","(-300,0)","0","mstr_discrete","I138";
;
WATTAGE"1/16W"
PACK_TYPE"0402"
VALUE"221"
TOLERANCE"1.0%"
MATERIAL"CHIP"
LOCATION"R9E24"
PART_NUMBER"G21796-271"
CDS_SEC"1"
CDS_LOCATION"R9E24"
CDS_LIB"mstr_discrete"
ROOM"BMC"
SEC_TYPE"0402"
BOM_COST"SM_CONTROLLER"
SEC"1";
"B"
$PN"2"5;
"A"
$PN"1"113;
%"CAP"
"1","(325,1425)","1","mstr_discrete","I139";
;
VALUE"1.0UF"
LOCATION"C25W2"
PACK_TYPE"0402"
PART_NUMBER"D97712-011"
MATERIAL"X6S"
TOLERANCE"10%"
VOLTAGE"16V"
CDS_SEC"1"
$SEC"1"
CDS_LOCATION"C25W2"
ROOM"VDDQ_KLM_PWR_VR"
CDS_LIB"mstr_discrete";
"A"
$PN"1"17;
"B"
$PN"2"6;
%"CAP"
"1","(325,1175)","1","mstr_discrete","I140";
;
TOLERANCE"10%"
MATERIAL"X6S"
PART_NUMBER"D97712-011"
PACK_TYPE"0402"
VOLTAGE"16V"
VALUE"1.0UF"
LOCATION"C25W3"
CDS_SEC"1"
$SEC"1"
CDS_LOCATION"C25W3"
CDS_LIB"mstr_discrete"
ROOM"VDDQ_KLM_PWR_VR";
"A"
$PN"1"17;
"B"
$PN"2"6;
%"CAP"
"1","(325,925)","1","mstr_discrete","I141";
;
PART_NUMBER"D97712-011"
LOCATION"C25W4"
PACK_TYPE"0402"
VALUE"1.0UF"
VOLTAGE"16V"
TOLERANCE"10%"
MATERIAL"X6S"
CDS_SEC"1"
$SEC"1"
CDS_LOCATION"C25W4"
CDS_LIB"mstr_discrete"
ROOM"VDDQ_KLM_PWR_VR";
"A"
$PN"1"17;
"B"
$PN"2"6;
%"CAP"
"1","(325,675)","1","mstr_discrete","I142";
;
LOCATION"C25W5"
VALUE"1.0UF"
VOLTAGE"16V"
TOLERANCE"10%"
MATERIAL"X6S"
PART_NUMBER"D97712-011"
PACK_TYPE"0402"
CDS_SEC"1"
$SEC"1"
CDS_LOCATION"C25W5"
CDS_LIB"mstr_discrete"
ROOM"VDDQ_KLM_PWR_VR";
"A"
$PN"1"17;
"B"
$PN"2"6;
%"CAP"
"1","(325,425)","1","mstr_discrete","I143";
;
TOLERANCE"10%"
VALUE"1.0UF"
PACK_TYPE"0402"
PART_NUMBER"D97712-011"
MATERIAL"X6S"
VOLTAGE"16V"
LOCATION"C25W6"
CDS_SEC"1"
$SEC"1"
CDS_LOCATION"C25W6"
CDS_LIB"mstr_discrete"
ROOM"VDDQ_KLM_PWR_VR";
"A"
$PN"1"17;
"B"
$PN"2"6;
%"LED"
"3","(-900,0)","0","mstr_discrete","I144";
;
LOCATION"DS9E1"
PART_NUMBER"C97278-010"
MATERIAL"IC"
COLOR"GREEN"
CDS_SEC"1"
CDS_LIB"mstr_discrete"
SEC"1"
CDS_LOCATION"DS9E1"
ROOM"BMC"
PACK_TYPE"A1LF"
SEC_TYPE"A1LF"
BOM_COST"SM_CONTROLLER";
"A"
$PN"1"113;
"C"
$PN"2"111;
%"FET_N_DUAL"
"5","(-1100,-375)","0","mstr_discrete","I145";
;
VALUE"NTJD4001N"
MATERIAL"FET"
PART_NUMBER"E40049-001"
LOCATION"Q9E1"
CDS_SEC"2"
CDS_LIB"mstr_discrete"
PACK_TYPE"SMLF"
CDS_LOCATION"Q9E1"
SEC"2"
BOM_COST"SM_CONTROLLER"
SEC_TYPE"SMLF"
ROOM"BMC";
"GATE <SIZE -1..0>"
$PN"5"89;
"SOURCE <SIZE-1..0>"
$PN"4"9;
"DRAIN <SIZE -1..0>"
$PN"3"111;
%"W_VCC_CIRCLE"
"1","(-150,-1350)","0","w_power","I146";
;
HDL_POWER"P1V2_AUX_BMC"
BODY_TYPE"PLUMBING"
CDS_LMAN_SYM_OUTLINE"-100,100,100,-100"
CDS_LIB"w_power";
"VCC_CIRCLE \B"7;
%"GND"
"1","(-150,-2150)","0","mstr_symbols","I149";
;
HDL_POWER"GND"
BODY_TYPE"PLUMBING"
CDS_LIB"mstr_symbols"
SIZE"1B"
VOLTAGE"0.0V";
"A\NAC"8;
%"GND"
"1","(-1100,-700)","0","mstr_symbols","I150";
;
HDL_POWER"GND"
BODY_TYPE"PLUMBING"
VOLTAGE"0.0V"
CDS_LIB"mstr_symbols"
SIZE"1B";
"A\NAC"9;
%"P3V3_STBY"
"1","(-1700,-75)","0","mstr_symbols","I172";
;
HDL_POWER"P3V3_STBY"
BODY_TYPE"PLUMBING"
VOLTAGE"3.3V"
SIZE"1B"
CDS_LIB"mstr_symbols";
"G\NAC"10;
%"RES"
"2","(-1700,-300)","0","mstr_discrete","I173";
;
PART_NUMBER"G21796-072"
VALUE"4.75K"
MATERIAL"CHIP"
PACK_TYPE"0402"
TOLERANCE"1%"
LOCATION"R9E21"
WATTAGE"1/16W"
CDS_SEC"1"
CDS_LIB"mstr_discrete"
CDS_LOCATION"R9E21"
ROOM"BMC"
SEC"1"
BOM_COST"SM_CONTROLLER"
SEC_TYPE"0402";
"A"
$PN"1"10;
"B"
$PN"2"89;
%"P3V3_STBY"
"1","(-2175,-225)","0","mstr_symbols","I174";
;
HDL_POWER"P3V3_STBY"
BODY_TYPE"PLUMBING"
VOLTAGE"3.3V"
CDS_LIB"mstr_symbols"
SIZE"1B";
"G\NAC"11;
%"RES"
"2","(-2175,-475)","0","mstr_discrete","I175";
;
LOCATION"R8B25"
MATERIAL"CHIP"
TOLERANCE"1%"
PACK_TYPE"0402"
PART_NUMBER"G21796-072"
WATTAGE"1/16W"
VALUE"4.75K"
CDS_SEC"1"
CDS_LIB"mstr_discrete"
BOM_COST"SM_CONTROLLER"
SEC_TYPE"0402"
SEC"1"
CDS_LOCATION"R8B25"
ROOM"BMC";
"A"
$PN"1"11;
"B"
$PN"2"110;
%"GND"
"1","(-3400,325)","0","mstr_symbols","I197";
;
HDL_POWER"GND"
BODY_TYPE"PLUMBING"
CDS_LIB"mstr_symbols"
VOLTAGE"0.0V"
SIZE"1B";
"A\NAC"12;
%"FET_N_DUAL"
"5","(-1700,-800)","0","mstr_discrete","I198";
;
PART_NUMBER"E40049-001"
VALUE"NTJD4001N"
LOCATION"Q9E1"
MATERIAL"FET"
CDS_SEC"1"
CDS_LIB"mstr_discrete"
CDS_LOCATION"Q9E1"
ROOM"BMC"
PACK_TYPE"SMLF"
SEC_TYPE"SMLF"
SEC"1"
BOM_COST"SM_CONTROLLER";
"GATE <SIZE -1..0>"
$PN"2"110;
"SOURCE <SIZE-1..0>"
$PN"1"13;
"DRAIN <SIZE -1..0>"
$PN"6"89;
%"GND"
"1","(-1700,-1100)","0","mstr_symbols","I199";
;
HDL_POWER"GND"
BODY_TYPE"PLUMBING"
VOLTAGE"0.0V"
SIZE"1B"
CDS_LIB"mstr_symbols";
"A\NAC"13;
%"W_VCC_CIRCLE"
"1","(-1675,-1250)","0","w_power","I200";
;
HDL_POWER"P1V2_AUX_BMC"
BODY_TYPE"PLUMBING"
CDS_LIB"w_power"
CDS_LMAN_SYM_OUTLINE"-100,100,100,-100";
"VCC_CIRCLE \B"14;
%"RES"
"2","(-1675,-1575)","0","mstr_discrete","I201";
;
PART_NUMBER"G21796-026"
WATTAGE"1/16W"
LOCATION"R1T30"
TOLERANCE"1%"
MATERIAL"CHIP"
PACK_TYPE"0402"
VALUE"1.00K"
SEC"1"
BOM_COST"SM_MEM"
CDS_LIB"mstr_discrete"
SEC_TYPE"0402"
ROOM"BMC_MEMORY"
CDS_LOCATION"R1T30"
CDS_SEC"1";
"A"
$PN"1"14;
"B"
$PN"2"75;
%"RES"
"2","(-1675,-2000)","0","mstr_discrete","I202";
;
WATTAGE"1/16W"
PART_NUMBER"G21796-026"
LOCATION"R1T29"
VALUE"1.00K"
TOLERANCE"1%"
MATERIAL"CHIP"
PACK_TYPE"0402"
SEC"1"
BOM_COST"SM_MEM"
CDS_LIB"mstr_discrete"
SEC_TYPE"0402"
ROOM"BMC_MEMORY"
CDS_LOCATION"R1T29"
CDS_SEC"1";
"A"
$PN"1"75;
"B"
$PN"2"15;
%"GND"
"1","(-1675,-2450)","0","mstr_symbols","I204";
;
HDL_POWER"GND"
BODY_TYPE"PLUMBING"
VOLTAGE"0.0V"
SIZE"1B"
CDS_LIB"mstr_symbols";
"A\NAC"15;
%"RES"
"2","(3125,1975)","1","mstr_discrete","I209";
;
CDS_SEC"1"
PART_NUMBER"G21796-074"
LOCATION"R9F34"
MATERIAL"EMPTY"
VALUE"33.2"
PACK_TYPE"0402"
WATTAGE"1/16W"
TOLERANCE"1%"
CDS_LOCATION"R9F34"
CDS_LIB"mstr_discrete"
ROOM"DEBUG"
SEC_TYPE"0402"
SEC"1";
"A"
$PN"1"27;
"B"
$PN"2"26;
%"RES"
"2","(-150,-1500)","2","mstr_discrete","I210";
;
CDS_SEC"1"
TOLERANCE"1%"
PACK_TYPE"0402"
PART_NUMBER"G21796-072"
WATTAGE"1/16W"
MATERIAL"EMPTY"
VALUE"4.75K"
LOCATION"R25W119"
CDS_LOCATION"R25W119"
SEC_TYPE"0402"
SEC"1"
CDS_LIB"mstr_discrete"
ROOM"SB_SPI"
BOM_COST"MIO_BIOS_MEM"
NO_XNET_CONNECTION"1";
"A"
$PN"1"7;
"B"
$PN"2"88;
%"RES"
"1","(-150,-1950)","5","mstr_discrete","I211";
;
CDS_SEC"1"
LOCATION"R25W118"
PART_NUMBER"G21497-005"
WATTAGE"1/16W"
VALUE"0.0"
MATERIAL"CHIP"
TOLERANCE"5%"
PACK_TYPE"0402"
CDS_LOCATION"R25W118"
SEC"1"
SEC_TYPE"0402"
CDS_LIB"mstr_discrete"
ROOM"HOT_SWAP";
"B"
$PN"2"8;
"A"
$PN"1"88;
%"CAP_A"
"1","(-1950,-2000)","0","dev_discrete","I212";
;
PART_NUMBER"D97712-004"
VOLTAGE"6.3V"
VALUE"1.0UF"
PACK_TYPE"0402V"
TOLERANCE"10%"
MATERIAL"X6S"
LOCATION"C25W12"
CDS_LOCATION"C25W12"
ROOM"VDDQ_KLM_PWR_VR"
SEC"1"
SEC_TYPE"0402V"
CDS_SEC"1"
CDS_LIB"dev_discrete";
"B"
$PN"2"15;
"A"
$PN"1"75;
%"CAP_A"
"1","(-2275,-1600)","2","dev_discrete","I213";
;
TOLERANCE"10%"
VOLTAGE"25V"
POP"NOPOP"
MATERIAL"X7R"
PART_NUMBER"A36096-045"
PACK_TYPE"0402V"
VALUE"0.01UF"
LOCATION"C25W10"
CDS_LOCATION"C25W10"
ROOM"DDR4_CH_M"
SEC"1"
SEC_TYPE"0402V"
CDS_SEC"1"
CDS_LIB"dev_discrete"
BOM_COST"MEM";
"B"
$PN"2"75;
"A"
$PN"1"14;
%"CAP_A"
"1","(-2275,-2000)","2","dev_discrete","I214";
;
VOLTAGE"25V"
LOCATION"C25W11"
PART_NUMBER"A36096-045"
VALUE"0.01UF"
TOLERANCE"10%"
PACK_TYPE"0402V"
MATERIAL"X7R"
CDS_LOCATION"C25W11"
BOM_COST"MEM"
CDS_LIB"dev_discrete"
CDS_SEC"1"
SEC_TYPE"0402V"
SEC"1"
ROOM"DDR4_CH_M";
"B"
$PN"2"15;
"A"
$PN"1"75;
%"CAP_A"
"1","(1100,550)","0","dev_discrete","I215";
;
TOLERANCE"10%"
LOCATION"C25W14"
VALUE"0.1UF"
PART_NUMBER"A36096-030"
VOLTAGE"16V"
PACK_TYPE"0402V"
MATERIAL"X7R"
CDS_LOCATION"C25W14"
CDS_LIB"dev_discrete"
CDS_SEC"1"
ROOM"VDDQ_KLM_PWR_VR"
SEC_TYPE"0402V"
SEC"1";
"B"
$PN"2"22;
"A"
$PN"1"21;
%"CAP_A"
"1","(1450,550)","0","dev_discrete","I216";
;
PACK_TYPE"0402V"
VALUE"0.1UF"
VOLTAGE"16V"
TOLERANCE"10%"
MATERIAL"X7R"
PART_NUMBER"A36096-030"
LOCATION"C25W15"
CDS_LOCATION"C25W15"
CDS_LIB"dev_discrete"
CDS_SEC"1"
ROOM"VDDQ_KLM_PWR_VR"
SEC_TYPE"0402V"
SEC"1";
"B"
$PN"2"22;
"A"
$PN"1"21;
%"CAP_A"
"1","(600,-100)","0","dev_discrete","I217";
;
PART_NUMBER"A36096-030"
MATERIAL"X7R"
PACK_TYPE"0402V"
VOLTAGE"16V"
TOLERANCE"10%"
VALUE"0.1UF"
LOCATION"C25W13"
CDS_LOCATION"C25W13"
SEC"1"
SEC_TYPE"0402V"
ROOM"VDDQ_KLM_PWR_VR"
CDS_SEC"1"
CDS_LIB"dev_discrete";
"B"
$PN"2"2;
"A"
$PN"1"36;
%"CAP"
"1","(1950,-1900)","2","mstr_discrete","I220";
;
CDS_SEC"1"
PART_NUMBER"A36096-155"
MATERIAL"X7R"
TOLERANCE"10%"
PACK_TYPE"0402"
LOCATION"C1W20"
VALUE"0.22UF"
VOLTAGE"16V"
CDS_LOCATION"C1W20"
CDS_LIB"mstr_discrete"
SEC_TYPE"0402"
SEC"1"
ROOM"OCP_STEERING";
"A"
$PN"1"38;
"B"
$PN"2"16;
%"GND"
"1","(1950,-2100)","0","mstr_symbols","I221";
;
HDL_POWER"GND"
BODY_TYPE"PLUMBING"
CDS_LIB"mstr_symbols"
SIZE"1B"
VOLTAGE"0.0V";
"A\NAC"16;
%"RES"
"2","(-975,1525)","1","mstr_discrete","I222";
;
CDS_SEC"1"
CDS_LOCATION"R25W30"
PACK_TYPE"0402"
WATTAGE"1/16W"
TOLERANCE"1%"
VALUE"2.7K"
MATERIAL"CHIP"
LOCATION"R25W30"
PART_NUMBER"G21796-344"
CDS_LIB"mstr_discrete"
SEC_TYPE"0402"
SEC"1";
"A"
$PN"1"66;
"B"
$PN"2"17;
%"120R2F-GP"
"1","(-950,1675)","1","w_hdl","I223";
;
CDS_SEC"1"
CDS_LOCATION"R25W27"
PACK_SIZE"0402"
RATED"1/16W"
ATTRIBUTE"120OHM"
LOCATION"R25W27"
TOLERANCE"1%"
VALUE"120R2F-GP"
PACK_TYPE"RCL_GP"
SEC"1"
SEC_TYPE"RCL_GP"
PART_NUMBER"64.12005.6DL"
CDS_LIB"w_hdl"
CDS_LMAN_SYM_OUTLINE"-50,75,50,-75";
"2"
$PN"2"17;
"1"
$PN"1"71;
%"120R2F-GP"
"1","(-950,1625)","1","w_hdl","I224";
;
CDS_SEC"1"
CDS_LOCATION"R25W28"
RATED"1/16W"
ATTRIBUTE"120OHM"
LOCATION"R25W28"
VALUE"120R2F-GP"
TOLERANCE"1%"
PACK_SIZE"0402"
CDS_LMAN_SYM_OUTLINE"-50,75,50,-75"
CDS_LIB"w_hdl"
PART_NUMBER"64.12005.6DL"
SEC_TYPE"RCL_GP"
SEC"1"
PACK_TYPE"RCL_GP";
"2"
$PN"2"17;
"1"
$PN"1"28;
%"120R2F-GP"
"1","(-950,1575)","1","w_hdl","I225";
;
CDS_SEC"1"
CDS_LOCATION"R25W29"
PACK_SIZE"0402"
POP"NOPOP"
LOCATION"R25W29"
RATED"1/16W"
TOLERANCE"1%"
ATTRIBUTE"120OHM"
VALUE"120R2F-GP"
CDS_LMAN_SYM_OUTLINE"-50,75,50,-75"
CDS_LIB"w_hdl"
PART_NUMBER"64.12005.6DL"
SEC_TYPE"RCL_GP"
SEC"1"
PACK_TYPE"RCL_GP";
"2"
$PN"2"17;
"1"
$PN"1"29;
%"120R2F-GP"
"1","(-950,1475)","1","w_hdl","I226";
;
CDS_SEC"1"
CDS_LOCATION"R25W31"
PACK_SIZE"0402"
ATTRIBUTE"120OHM"
LOCATION"R25W31"
VALUE"120R2F-GP"
RATED"1/16W"
TOLERANCE"1%"
PACK_TYPE"RCL_GP"
SEC"1"
SEC_TYPE"RCL_GP"
PART_NUMBER"64.12005.6DL"
CDS_LIB"w_hdl"
CDS_LMAN_SYM_OUTLINE"-50,75,50,-75";
"2"
$PN"2"17;
"1"
$PN"1"65;
%"120R2F-GP"
"1","(-950,1425)","1","w_hdl","I227";
;
CDS_SEC"1"
CDS_LOCATION"R25W32"
PACK_SIZE"0402"
ATTRIBUTE"120OHM"
LOCATION"R25W32"
VALUE"120R2F-GP"
RATED"1/16W"
TOLERANCE"1%"
PACK_TYPE"RCL_GP"
SEC"1"
SEC_TYPE"RCL_GP"
PART_NUMBER"64.12005.6DL"
CDS_LIB"w_hdl"
CDS_LMAN_SYM_OUTLINE"-50,75,50,-75";
"2"
$PN"2"17;
"1"
$PN"1"70;
%"120R2F-GP"
"1","(-950,1375)","1","w_hdl","I228";
;
CDS_SEC"1"
CDS_LOCATION"R25W33"
LOCATION"R25W33"
PACK_SIZE"0402"
ATTRIBUTE"120OHM"
RATED"1/16W"
TOLERANCE"1%"
VALUE"120R2F-GP"
PACK_TYPE"RCL_GP"
SEC"1"
SEC_TYPE"RCL_GP"
PART_NUMBER"64.12005.6DL"
CDS_LIB"w_hdl"
CDS_LMAN_SYM_OUTLINE"-50,75,50,-75";
"2"
$PN"2"17;
"1"
$PN"1"64;
%"120R2F-GP"
"1","(-950,1325)","1","w_hdl","I229";
;
CDS_SEC"1"
CDS_LOCATION"R25W34"
PACK_SIZE"0402"
ATTRIBUTE"120OHM"
VALUE"120R2F-GP"
RATED"1/16W"
TOLERANCE"1%"
LOCATION"R25W34"
PACK_TYPE"RCL_GP"
SEC"1"
SEC_TYPE"RCL_GP"
PART_NUMBER"64.12005.6DL"
CDS_LIB"w_hdl"
CDS_LMAN_SYM_OUTLINE"-50,75,50,-75";
"2"
$PN"2"17;
"1"
$PN"1"63;
%"120R2F-GP"
"1","(-950,1275)","1","w_hdl","I230";
;
CDS_SEC"1"
CDS_LOCATION"R25W35"
PACK_SIZE"0402"
ATTRIBUTE"120OHM"
VALUE"120R2F-GP"
RATED"1/16W"
TOLERANCE"1%"
LOCATION"R25W35"
PACK_TYPE"RCL_GP"
SEC"1"
SEC_TYPE"RCL_GP"
PART_NUMBER"64.12005.6DL"
CDS_LIB"w_hdl"
CDS_LMAN_SYM_OUTLINE"-50,75,50,-75";
"2"
$PN"2"17;
"1"
$PN"1"69;
%"120R2F-GP"
"1","(-950,1225)","1","w_hdl","I231";
;
CDS_SEC"1"
CDS_LOCATION"R25W36"
PACK_SIZE"0402"
ATTRIBUTE"120OHM"
VALUE"120R2F-GP"
TOLERANCE"1%"
LOCATION"R25W36"
RATED"1/16W"
PACK_TYPE"RCL_GP"
SEC"1"
SEC_TYPE"RCL_GP"
PART_NUMBER"64.12005.6DL"
CDS_LIB"w_hdl"
CDS_LMAN_SYM_OUTLINE"-50,75,50,-75";
"2"
$PN"2"17;
"1"
$PN"1"62;
%"120R2F-GP"
"1","(-950,1175)","1","w_hdl","I232";
;
CDS_SEC"1"
CDS_LOCATION"R25W37"
LOCATION"R25W37"
ATTRIBUTE"120OHM"
VALUE"120R2F-GP"
RATED"1/16W"
TOLERANCE"1%"
PACK_SIZE"0402"
PACK_TYPE"RCL_GP"
SEC"1"
SEC_TYPE"RCL_GP"
PART_NUMBER"64.12005.6DL"
CDS_LIB"w_hdl"
CDS_LMAN_SYM_OUTLINE"-50,75,50,-75";
"2"
$PN"2"17;
"1"
$PN"1"68;
%"120R2F-GP"
"1","(-950,1125)","1","w_hdl","I233";
;
CDS_SEC"1"
CDS_LOCATION"R25W38"
LOCATION"R25W38"
ATTRIBUTE"120OHM"
VALUE"120R2F-GP"
RATED"1/16W"
TOLERANCE"1%"
PACK_SIZE"0402"
PACK_TYPE"RCL_GP"
SEC"1"
SEC_TYPE"RCL_GP"
PART_NUMBER"64.12005.6DL"
CDS_LIB"w_hdl"
CDS_LMAN_SYM_OUTLINE"-50,75,50,-75";
"2"
$PN"2"17;
"1"
$PN"1"67;
%"120R2F-GP"
"1","(-950,1075)","1","w_hdl","I234";
;
CDS_SEC"1"
CDS_LOCATION"R25W39"
LOCATION"R25W39"
RATED"1/16W"
ATTRIBUTE"120OHM"
VALUE"120R2F-GP"
TOLERANCE"1%"
PACK_SIZE"0402"
PACK_TYPE"RCL_GP"
SEC"1"
SEC_TYPE"RCL_GP"
PART_NUMBER"64.12005.6DL"
CDS_LIB"w_hdl"
CDS_LMAN_SYM_OUTLINE"-50,75,50,-75";
"2"
$PN"2"17;
"1"
$PN"1"61;
%"120R2F-GP"
"1","(-950,975)","1","w_hdl","I235";
;
CDS_SEC"1"
CDS_LOCATION"R25W41"
LOCATION"R25W41"
ATTRIBUTE"120OHM"
VALUE"120R2F-GP"
TOLERANCE"1%"
RATED"1/16W"
PACK_SIZE"0402"
CDS_LMAN_SYM_OUTLINE"-50,75,50,-75"
CDS_LIB"w_hdl"
PART_NUMBER"64.12005.6DL"
SEC_TYPE"RCL_GP"
SEC"1"
PACK_TYPE"RCL_GP";
"2"
$PN"2"17;
"1"
$PN"1"23;
%"120R2F-GP"
"1","(-950,925)","1","w_hdl","I236";
;
CDS_SEC"1"
CDS_LOCATION"R25W42"
LOCATION"R25W42"
PACK_SIZE"0402"
ATTRIBUTE"120OHM"
TOLERANCE"1%"
VALUE"120R2F-GP"
RATED"1/16W"
CDS_LMAN_SYM_OUTLINE"-50,75,50,-75"
CDS_LIB"w_hdl"
PART_NUMBER"64.12005.6DL"
SEC_TYPE"RCL_GP"
SEC"1"
PACK_TYPE"RCL_GP";
"2"
$PN"2"17;
"1"
$PN"1"55;
%"120R2F-GP"
"1","(-950,825)","1","w_hdl","I237";
;
CDS_SEC"1"
CDS_LOCATION"R25W44"
LOCATION"R25W44"
PACK_SIZE"0402"
RATED"1/16W"
VALUE"120R2F-GP"
ATTRIBUTE"120OHM"
TOLERANCE"1%"
CDS_LMAN_SYM_OUTLINE"-50,75,50,-75"
CDS_LIB"w_hdl"
PART_NUMBER"64.12005.6DL"
SEC_TYPE"RCL_GP"
SEC"1"
PACK_TYPE"RCL_GP";
"2"
$PN"2"17;
"1"
$PN"1"57;
%"120R2F-GP"
"1","(-950,875)","1","w_hdl","I238";
;
CDS_SEC"1"
CDS_LOCATION"R25W43"
LOCATION"R25W43"
PACK_SIZE"0402"
VALUE"120R2F-GP"
ATTRIBUTE"120OHM"
TOLERANCE"1%"
RATED"1/16W"
CDS_LMAN_SYM_OUTLINE"-50,75,50,-75"
CDS_LIB"w_hdl"
PART_NUMBER"64.12005.6DL"
SEC_TYPE"RCL_GP"
SEC"1"
PACK_TYPE"RCL_GP";
"2"
$PN"2"17;
"1"
$PN"1"56;
%"120R2F-GP"
"1","(-950,675)","1","w_hdl","I239";
;
CDS_SEC"1"
CDS_LOCATION"R25W47"
LOCATION"R25W47"
PACK_SIZE"0402"
ATTRIBUTE"120OHM"
VALUE"120R2F-GP"
TOLERANCE"1%"
RATED"1/16W"
CDS_LMAN_SYM_OUTLINE"-50,75,50,-75"
CDS_LIB"w_hdl"
PART_NUMBER"64.12005.6DL"
SEC_TYPE"RCL_GP"
SEC"1"
PACK_TYPE"RCL_GP";
"2"
$PN"2"17;
"1"
$PN"1"30;
%"120R2F-GP"
"1","(-950,625)","1","w_hdl","I240";
;
CDS_SEC"1"
CDS_LOCATION"R25W48"
PACK_SIZE"0402"
ATTRIBUTE"120OHM"
TOLERANCE"1%"
RATED"1/16W"
VALUE"120R2F-GP"
LOCATION"R25W48"
CDS_LMAN_SYM_OUTLINE"-50,75,50,-75"
CDS_LIB"w_hdl"
PART_NUMBER"64.12005.6DL"
SEC_TYPE"RCL_GP"
SEC"1"
PACK_TYPE"RCL_GP";
"2"
$PN"2"17;
"1"
$PN"1"31;
%"120R2F-GP"
"1","(-950,725)","1","w_hdl","I241";
;
CDS_SEC"1"
CDS_LOCATION"R25W46"
LOCATION"R25W46"
PACK_SIZE"0402"
TOLERANCE"1%"
RATED"1/16W"
VALUE"120R2F-GP"
ATTRIBUTE"120OHM"
CDS_LMAN_SYM_OUTLINE"-50,75,50,-75"
CDS_LIB"w_hdl"
PART_NUMBER"64.12005.6DL"
SEC_TYPE"RCL_GP"
SEC"1"
PACK_TYPE"RCL_GP";
"2"
$PN"2"17;
"1"
$PN"1"59;
%"120R2F-GP"
"1","(-950,775)","1","w_hdl","I242";
;
CDS_SEC"1"
CDS_LOCATION"R25W45"
LOCATION"R25W45"
VALUE"120R2F-GP"
ATTRIBUTE"120OHM"
TOLERANCE"1%"
RATED"1/16W"
PACK_SIZE"0402"
CDS_LMAN_SYM_OUTLINE"-50,75,50,-75"
CDS_LIB"w_hdl"
PART_NUMBER"64.12005.6DL"
SEC_TYPE"RCL_GP"
SEC"1"
PACK_TYPE"RCL_GP";
"2"
$PN"2"17;
"1"
$PN"1"58;
%"120R2F-GP"
"1","(-950,575)","1","w_hdl","I243";
;
CDS_SEC"1"
CDS_LOCATION"R25W49"
PACK_SIZE"0402"
LOCATION"R25W49"
TOLERANCE"1%"
RATED"1/16W"
ATTRIBUTE"120OHM"
VALUE"120R2F-GP"
CDS_LMAN_SYM_OUTLINE"-50,75,50,-75"
CDS_LIB"w_hdl"
PART_NUMBER"64.12005.6DL"
SEC_TYPE"RCL_GP"
SEC"1"
PACK_TYPE"RCL_GP";
"2"
$PN"2"17;
"1"
$PN"1"32;
%"120R2F-GP"
"1","(-950,525)","1","w_hdl","I244";
;
CDS_SEC"1"
CDS_LOCATION"R25W50"
PACK_SIZE"0402"
LOCATION"R25W50"
RATED"1/16W"
VALUE"120R2F-GP"
ATTRIBUTE"120OHM"
TOLERANCE"1%"
CDS_LMAN_SYM_OUTLINE"-50,75,50,-75"
CDS_LIB"w_hdl"
PART_NUMBER"64.12005.6DL"
SEC_TYPE"RCL_GP"
SEC"1"
PACK_TYPE"RCL_GP";
"2"
$PN"2"17;
"1"
$PN"1"33;
%"120R2F-GP"
"1","(-950,475)","1","w_hdl","I245";
;
CDS_SEC"1"
CDS_LOCATION"R25W51"
ATTRIBUTE"120OHM"
VALUE"120R2F-GP"
TOLERANCE"1%"
LOCATION"R25W51"
RATED"1/16W"
PACK_SIZE"0402"
CDS_LMAN_SYM_OUTLINE"-50,75,50,-75"
CDS_LIB"w_hdl"
PART_NUMBER"64.12005.6DL"
SEC_TYPE"RCL_GP"
SEC"1"
PACK_TYPE"RCL_GP";
"2"
$PN"2"17;
"1"
$PN"1"34;
%"120R2F-GP"
"1","(-950,425)","1","w_hdl","I246";
;
CDS_SEC"1"
CDS_LOCATION"R25W52"
ATTRIBUTE"120OHM"
VALUE"120R2F-GP"
TOLERANCE"1%"
RATED"1/16W"
LOCATION"R25W52"
PACK_SIZE"0402"
CDS_LMAN_SYM_OUTLINE"-50,75,50,-75"
CDS_LIB"w_hdl"
PART_NUMBER"64.12005.6DL"
SEC_TYPE"RCL_GP"
SEC"1"
PACK_TYPE"RCL_GP";
"2"
$PN"2"17;
"1"
$PN"1"35;
%"120R2F-GP"
"1","(-950,1025)","1","w_hdl","I247";
;
CDS_SEC"1"
CDS_LOCATION"R25W40"
LOCATION"R25W40"
TOLERANCE"1%"
ATTRIBUTE"120OHM"
VALUE"120R2F-GP"
RATED"1/16W"
PACK_SIZE"0402"
CDS_LMAN_SYM_OUTLINE"-50,75,50,-75"
CDS_LIB"w_hdl"
PART_NUMBER"64.12005.6DL"
SEC_TYPE"RCL_GP"
SEC"1"
PACK_TYPE"RCL_GP";
"2"
$PN"2"17;
"1"
$PN"1"60;
%"120R2F-GP"
"1","(-3025,1675)","1","w_hdl","I248";
;
CDS_SEC"1"
CDS_LOCATION"R25W1"
ATTRIBUTE"120OHM"
RATED"1/16W"
TOLERANCE"1%"
LOCATION"R25W1"
PACK_SIZE"0402"
VALUE"120R2F-GP"
CDS_LMAN_SYM_OUTLINE"-50,75,50,-75"
CDS_LIB"w_hdl"
PART_NUMBER"64.12005.6DL"
SEC_TYPE"RCL_GP"
SEC"1"
PACK_TYPE"RCL_GP";
"2"
$PN"2"71;
"1"
$PN"1"12;
%"120R2F-GP"
"1","(-3025,1625)","1","w_hdl","I249";
;
CDS_SEC"1"
CDS_LOCATION"R25W2"
ATTRIBUTE"120OHM"
TOLERANCE"1%"
RATED"1/16W"
VALUE"120R2F-GP"
PACK_SIZE"0402"
LOCATION"R25W2"
PACK_TYPE"RCL_GP"
SEC"1"
SEC_TYPE"RCL_GP"
PART_NUMBER"64.12005.6DL"
CDS_LIB"w_hdl"
CDS_LMAN_SYM_OUTLINE"-50,75,50,-75";
"2"
$PN"2"28;
"1"
$PN"1"12;
%"120R2F-GP"
"1","(-3025,1575)","1","w_hdl","I250";
;
CDS_SEC"1"
CDS_LOCATION"R25W3"
TOLERANCE"1%"
POP"NOPOP"
LOCATION"R25W3"
RATED"1/16W"
ATTRIBUTE"120OHM"
VALUE"120R2F-GP"
PACK_SIZE"0402"
PACK_TYPE"RCL_GP"
SEC"1"
SEC_TYPE"RCL_GP"
PART_NUMBER"64.12005.6DL"
CDS_LIB"w_hdl"
CDS_LMAN_SYM_OUTLINE"-50,75,50,-75";
"2"
$PN"2"29;
"1"
$PN"1"12;
%"120R2F-GP"
"1","(-3025,1525)","1","w_hdl","I251";
;
CDS_SEC"1"
CDS_LOCATION"R25W4"
VALUE"120R2F-GP"
RATED"1/16W"
POP"NOPOP"
LOCATION"R25W4"
TOLERANCE"1%"
ATTRIBUTE"120OHM"
PACK_SIZE"0402"
PACK_TYPE"RCL_GP"
SEC"1"
SEC_TYPE"RCL_GP"
PART_NUMBER"64.12005.6DL"
CDS_LIB"w_hdl"
CDS_LMAN_SYM_OUTLINE"-50,75,50,-75";
"2"
$PN"2"66;
"1"
$PN"1"12;
%"120R2F-GP"
"1","(-3025,1475)","1","w_hdl","I252";
;
CDS_SEC"1"
CDS_LOCATION"R25W5"
VALUE"120R2F-GP"
RATED"1/16W"
LOCATION"R25W5"
TOLERANCE"1%"
ATTRIBUTE"120OHM"
PACK_SIZE"0402"
CDS_LMAN_SYM_OUTLINE"-50,75,50,-75"
CDS_LIB"w_hdl"
PART_NUMBER"64.12005.6DL"
SEC_TYPE"RCL_GP"
SEC"1"
PACK_TYPE"RCL_GP";
"2"
$PN"2"65;
"1"
$PN"1"12;
%"120R2F-GP"
"1","(-3025,1425)","1","w_hdl","I253";
;
CDS_SEC"1"
CDS_LOCATION"R25W6"
RATED"1/16W"
LOCATION"R25W6"
VALUE"120R2F-GP"
TOLERANCE"1%"
ATTRIBUTE"120OHM"
PACK_SIZE"0402"
CDS_LMAN_SYM_OUTLINE"-50,75,50,-75"
CDS_LIB"w_hdl"
PART_NUMBER"64.12005.6DL"
SEC_TYPE"RCL_GP"
SEC"1"
PACK_TYPE"RCL_GP";
"2"
$PN"2"70;
"1"
$PN"1"12;
%"120R2F-GP"
"1","(-3025,1375)","1","w_hdl","I254";
;
CDS_SEC"1"
CDS_LOCATION"R25W7"
RATED"1/16W"
TOLERANCE"1%"
LOCATION"R25W7"
VALUE"120R2F-GP"
ATTRIBUTE"120OHM"
PACK_SIZE"0402"
CDS_LMAN_SYM_OUTLINE"-50,75,50,-75"
CDS_LIB"w_hdl"
PART_NUMBER"64.12005.6DL"
SEC_TYPE"RCL_GP"
SEC"1"
PACK_TYPE"RCL_GP";
"2"
$PN"2"64;
"1"
$PN"1"12;
%"120R2F-GP"
"1","(-3025,1325)","1","w_hdl","I255";
;
CDS_SEC"1"
CDS_LOCATION"R25W8"
ATTRIBUTE"120OHM"
RATED"1/16W"
LOCATION"R25W8"
VALUE"120R2F-GP"
TOLERANCE"1%"
PACK_SIZE"0402"
CDS_LMAN_SYM_OUTLINE"-50,75,50,-75"
CDS_LIB"w_hdl"
PART_NUMBER"64.12005.6DL"
SEC_TYPE"RCL_GP"
SEC"1"
PACK_TYPE"RCL_GP";
"2"
$PN"2"63;
"1"
$PN"1"12;
%"120R2F-GP"
"1","(-3025,1125)","1","w_hdl","I256";
;
CDS_SEC"1"
CDS_LOCATION"R25W12"
ATTRIBUTE"120OHM"
TOLERANCE"1%"
VALUE"120R2F-GP"
LOCATION"R25W12"
RATED"1/16W"
PACK_SIZE"0402"
CDS_LMAN_SYM_OUTLINE"-50,75,50,-75"
CDS_LIB"w_hdl"
PART_NUMBER"64.12005.6DL"
SEC_TYPE"RCL_GP"
SEC"1"
PACK_TYPE"RCL_GP";
"2"
$PN"2"67;
"1"
$PN"1"12;
%"120R2F-GP"
"1","(-3025,1175)","1","w_hdl","I257";
;
CDS_SEC"1"
CDS_LOCATION"R25W11"
ATTRIBUTE"120OHM"
RATED"1/16W"
VALUE"120R2F-GP"
LOCATION"R25W11"
TOLERANCE"1%"
PACK_SIZE"0402"
CDS_LMAN_SYM_OUTLINE"-50,75,50,-75"
CDS_LIB"w_hdl"
PART_NUMBER"64.12005.6DL"
SEC_TYPE"RCL_GP"
SEC"1"
PACK_TYPE"RCL_GP";
"2"
$PN"2"68;
"1"
$PN"1"12;
%"120R2F-GP"
"1","(-3025,1275)","1","w_hdl","I258";
;
CDS_SEC"1"
CDS_LOCATION"R25W9"
ATTRIBUTE"120OHM"
LOCATION"R25W9"
VALUE"120R2F-GP"
TOLERANCE"1%"
RATED"1/16W"
PACK_SIZE"0402"
CDS_LMAN_SYM_OUTLINE"-50,75,50,-75"
CDS_LIB"w_hdl"
PART_NUMBER"64.12005.6DL"
SEC_TYPE"RCL_GP"
SEC"1"
PACK_TYPE"RCL_GP";
"2"
$PN"2"69;
"1"
$PN"1"12;
%"120R2F-GP"
"1","(-3025,1225)","1","w_hdl","I259";
;
CDS_SEC"1"
CDS_LOCATION"R25W10"
ATTRIBUTE"120OHM"
LOCATION"R25W10"
VALUE"120R2F-GP"
TOLERANCE"1%"
RATED"1/16W"
PACK_SIZE"0402"
CDS_LMAN_SYM_OUTLINE"-50,75,50,-75"
CDS_LIB"w_hdl"
PART_NUMBER"64.12005.6DL"
SEC_TYPE"RCL_GP"
SEC"1"
PACK_TYPE"RCL_GP";
"2"
$PN"2"62;
"1"
$PN"1"12;
%"120R2F-GP"
"1","(-3025,1075)","1","w_hdl","I260";
;
CDS_SEC"1"
CDS_LOCATION"R25W13"
ATTRIBUTE"120OHM"
TOLERANCE"1%"
VALUE"120R2F-GP"
LOCATION"R25W13"
RATED"1/16W"
PACK_SIZE"0402"
CDS_LMAN_SYM_OUTLINE"-50,75,50,-75"
CDS_LIB"w_hdl"
PART_NUMBER"64.12005.6DL"
SEC_TYPE"RCL_GP"
SEC"1"
PACK_TYPE"RCL_GP";
"2"
$PN"2"61;
"1"
$PN"1"12;
%"120R2F-GP"
"1","(-3025,925)","1","w_hdl","I261";
;
CDS_SEC"1"
CDS_LOCATION"R25W16"
ATTRIBUTE"120OHM"
RATED"1/16W"
TOLERANCE"1%"
VALUE"120R2F-GP"
LOCATION"R25W16"
PACK_SIZE"0402"
PACK_TYPE"RCL_GP"
SEC"1"
SEC_TYPE"RCL_GP"
PART_NUMBER"64.12005.6DL"
CDS_LIB"w_hdl"
CDS_LMAN_SYM_OUTLINE"-50,75,50,-75";
"2"
$PN"2"55;
"1"
$PN"1"12;
%"120R2F-GP"
"1","(-3025,975)","1","w_hdl","I262";
;
CDS_SEC"1"
CDS_LOCATION"R25W15"
ATTRIBUTE"120OHM"
RATED"1/16W"
TOLERANCE"1%"
VALUE"120R2F-GP"
LOCATION"R25W15"
PACK_SIZE"0402"
CDS_LMAN_SYM_OUTLINE"-50,75,50,-75"
CDS_LIB"w_hdl"
PART_NUMBER"64.12005.6DL"
SEC_TYPE"RCL_GP"
SEC"1"
PACK_TYPE"RCL_GP";
"2"
$PN"2"23;
"1"
$PN"1"12;
%"120R2F-GP"
"1","(-3025,1025)","1","w_hdl","I263";
;
CDS_SEC"1"
CDS_LOCATION"R25W14"
ATTRIBUTE"120OHM"
TOLERANCE"1%"
VALUE"120R2F-GP"
LOCATION"R25W14"
RATED"1/16W"
PACK_SIZE"0402"
CDS_LMAN_SYM_OUTLINE"-50,75,50,-75"
CDS_LIB"w_hdl"
PART_NUMBER"64.12005.6DL"
SEC_TYPE"RCL_GP"
SEC"1"
PACK_TYPE"RCL_GP";
"2"
$PN"2"60;
"1"
$PN"1"12;
%"120R2F-GP"
"1","(-3025,875)","1","w_hdl","I264";
;
CDS_SEC"1"
CDS_LOCATION"R25W17"
ATTRIBUTE"120OHM"
LOCATION"R25W17"
RATED"1/16W"
TOLERANCE"1%"
VALUE"120R2F-GP"
PACK_SIZE"0402"
PACK_TYPE"RCL_GP"
SEC"1"
SEC_TYPE"RCL_GP"
PART_NUMBER"64.12005.6DL"
CDS_LIB"w_hdl"
CDS_LMAN_SYM_OUTLINE"-50,75,50,-75";
"2"
$PN"2"56;
"1"
$PN"1"12;
%"120R2F-GP"
"1","(-3025,825)","1","w_hdl","I265";
;
CDS_SEC"1"
CDS_LOCATION"R25W18"
ATTRIBUTE"120OHM"
LOCATION"R25W18"
RATED"1/16W"
TOLERANCE"1%"
VALUE"120R2F-GP"
PACK_SIZE"0402"
PACK_TYPE"RCL_GP"
SEC"1"
SEC_TYPE"RCL_GP"
PART_NUMBER"64.12005.6DL"
CDS_LIB"w_hdl"
CDS_LMAN_SYM_OUTLINE"-50,75,50,-75";
"2"
$PN"2"57;
"1"
$PN"1"12;
%"120R2F-GP"
"1","(-3025,725)","1","w_hdl","I266";
;
CDS_SEC"1"
CDS_LOCATION"R25W20"
ATTRIBUTE"120OHM"
VALUE"120R2F-GP"
LOCATION"R25W20"
RATED"1/16W"
TOLERANCE"1%"
PACK_SIZE"0402"
PACK_TYPE"RCL_GP"
SEC"1"
SEC_TYPE"RCL_GP"
PART_NUMBER"64.12005.6DL"
CDS_LIB"w_hdl"
CDS_LMAN_SYM_OUTLINE"-50,75,50,-75";
"2"
$PN"2"59;
"1"
$PN"1"12;
%"120R2F-GP"
"1","(-3025,775)","1","w_hdl","I267";
;
CDS_SEC"1"
CDS_LOCATION"R25W19"
ATTRIBUTE"120OHM"
VALUE"120R2F-GP"
LOCATION"R25W19"
RATED"1/16W"
TOLERANCE"1%"
PACK_SIZE"0402"
PACK_TYPE"RCL_GP"
SEC"1"
SEC_TYPE"RCL_GP"
PART_NUMBER"64.12005.6DL"
CDS_LIB"w_hdl"
CDS_LMAN_SYM_OUTLINE"-50,75,50,-75";
"2"
$PN"2"58;
"1"
$PN"1"12;
%"120R2F-GP"
"1","(-3025,525)","1","w_hdl","I268";
;
CDS_SEC"1"
CDS_LOCATION"R25W24"
ATTRIBUTE"120OHM"
VALUE"120R2F-GP"
LOCATION"R25W24"
TOLERANCE"1%"
RATED"1/16W"
PACK_SIZE"0402"
PACK_TYPE"RCL_GP"
SEC"1"
SEC_TYPE"RCL_GP"
PART_NUMBER"64.12005.6DL"
CDS_LIB"w_hdl"
CDS_LMAN_SYM_OUTLINE"-50,75,50,-75";
"2"
$PN"2"33;
"1"
$PN"1"12;
%"120R2F-GP"
"1","(-3025,575)","1","w_hdl","I269";
;
CDS_SEC"1"
CDS_LOCATION"R25W23"
ATTRIBUTE"120OHM"
VALUE"120R2F-GP"
LOCATION"R25W23"
RATED"1/16W"
TOLERANCE"1%"
PACK_SIZE"0402"
PACK_TYPE"RCL_GP"
SEC"1"
SEC_TYPE"RCL_GP"
PART_NUMBER"64.12005.6DL"
CDS_LIB"w_hdl"
CDS_LMAN_SYM_OUTLINE"-50,75,50,-75";
"2"
$PN"2"32;
"1"
$PN"1"12;
%"120R2F-GP"
"1","(-3025,625)","1","w_hdl","I270";
;
CDS_SEC"1"
CDS_LOCATION"R25W22"
ATTRIBUTE"120OHM"
VALUE"120R2F-GP"
LOCATION"R25W22"
RATED"1/16W"
TOLERANCE"1%"
PACK_SIZE"0402"
PACK_TYPE"RCL_GP"
SEC"1"
SEC_TYPE"RCL_GP"
PART_NUMBER"64.12005.6DL"
CDS_LIB"w_hdl"
CDS_LMAN_SYM_OUTLINE"-50,75,50,-75";
"2"
$PN"2"31;
"1"
$PN"1"12;
%"120R2F-GP"
"1","(-3025,675)","1","w_hdl","I271";
;
CDS_SEC"1"
CDS_LOCATION"R25W21"
ATTRIBUTE"120OHM"
VALUE"120R2F-GP"
LOCATION"R25W21"
RATED"1/16W"
TOLERANCE"1%"
PACK_SIZE"0402"
PACK_TYPE"RCL_GP"
SEC"1"
SEC_TYPE"RCL_GP"
PART_NUMBER"64.12005.6DL"
CDS_LIB"w_hdl"
CDS_LMAN_SYM_OUTLINE"-50,75,50,-75";
"2"
$PN"2"30;
"1"
$PN"1"12;
%"120R2F-GP"
"1","(-3025,425)","1","w_hdl","I274";
;
CDS_SEC"1"
CDS_LOCATION"R25W26"
ATTRIBUTE"120OHM"
LOCATION"R25W26"
RATED"1/16W"
TOLERANCE"1%"
VALUE"120R2F-GP"
PACK_SIZE"0402"
PACK_TYPE"RCL_GP"
SEC"1"
SEC_TYPE"RCL_GP"
PART_NUMBER"64.12005.6DL"
CDS_LIB"w_hdl"
CDS_LMAN_SYM_OUTLINE"-50,75,50,-75";
"2"
$PN"2"35;
"1"
$PN"1"12;
%"120R2F-GP"
"1","(-3025,475)","1","w_hdl","I275";
;
CDS_SEC"1"
CDS_LOCATION"R25W25"
ATTRIBUTE"120OHM"
VALUE"120R2F-GP"
LOCATION"R25W25"
TOLERANCE"1%"
RATED"1/16W"
PACK_SIZE"0402"
PACK_TYPE"RCL_GP"
SEC"1"
SEC_TYPE"RCL_GP"
PART_NUMBER"64.12005.6DL"
CDS_LIB"w_hdl"
CDS_LMAN_SYM_OUTLINE"-50,75,50,-75";
"2"
$PN"2"34;
"1"
$PN"1"12;
%"RES"
"1","(1250,-1550)","0","mstr_discrete","I278";
;
CDS_SEC"1"
PART_NUMBER"G21796-047"
TOLERANCE"1%"
WATTAGE"1/16W"
VALUE"49.9"
PACK_TYPE"0402"
MATERIAL"CHIP"
LOCATION"R1T40"
CDS_LOCATION"R1T40"
ROOM"CPU0"
SEC"1"
BOM_COST"PROC_SOCKET"
SEC_TYPE"0402"
CDS_LIB"mstr_discrete";
"B"
$PN"2"38;
"A"
$PN"1"44;
%"RES"
"1","(1250,-1950)","0","mstr_discrete","I279";
;
CDS_SEC"1"
VALUE"49.9"
WATTAGE"1/16W"
LOCATION"R1T28"
MATERIAL"CHIP"
PACK_TYPE"0402"
TOLERANCE"1%"
PART_NUMBER"G21796-047"
CDS_LOCATION"R1T28"
ROOM"CPU0"
SEC"1"
BOM_COST"PROC_SOCKET"
SEC_TYPE"0402"
CDS_LIB"mstr_discrete";
"B"
$PN"2"38;
"A"
$PN"1"39;
%"H5AN4G6NAFR-TFC-GP"
"1","(2650,25)","0","w_hdl","I49";
;
VALUE"H5AN4G6NAFR-TFC-GP"
LOCATION"U25W5"
PACK_TYPE"MEMORY-G2"
PART_NUMBER"072.00546.0A0U"
CDS_LIB"w_hdl"
CDS_LMAN_SYM_OUTLINE"-325,1525,325,-1525"
CDS_LOCATION"U25W5"
$SEC"1"
CDS_SEC"1";
"BA1"
$PN"N8"40;
"BA0"
$PN"N2"41;
"DML#/DBIL# \B"
$PN"E7"42;
"DMU#/DBIU# \B"
$PN"E2"43;
"DQSL_T"
$PN"G3"45;
"DQSL_C"
$PN"F3"82;
"DQSU_T"
$PN"B7"46;
"DQSU_C"
$PN"A7"81;
"VSSQ<9>"
$PN"H9"19;
"VSSQ<8>"
$PN"H1"19;
"VSSQ<7>"
$PN"F1"19;
"VSSQ<6>"
$PN"E8"19;
"VSSQ<5>"
$PN"E3"19;
"VSSQ<4>"
$PN"D8"19;
"VSSQ<3>"
$PN"D2"19;
"VSSQ<2>"
$PN"C9"19;
"VSSQ<1>"
$PN"A8"19;
"VSSQ<0>"
$PN"A2"19;
"VSS<8>"
$PN"T1"19;
"VSS<7>"
$PN"N1"19;
"VSS<6>"
$PN"M9"19;
"VSS<5>"
$PN"K9"19;
"VSS<4>"
$PN"K1"19;
"VSS<3>"
$PN"G8"19;
"VSS<2>"
$PN"E9"19;
"VSS<1>"
$PN"E1"19;
"VSS<0>"
$PN"B2"19;
"ALERT# \B"
$PN"P9"87;
"RESET# \B"
$PN"P1"93;
"CS# \B"
$PN"L7"92;
"ACT# \B"
$PN"L3"109;
"VPP<1>"
$PN"R9"21;
"CK_C"
$PN"K8"108;
"CK_T"
$PN"K7"76;
"NC#T7"
$PN"T7"0;
"PAR"
$PN"T3"85;
"TEN"
$PN"N9"19;
"BG0"
$PN"M2"91;
"ODT"
$PN"K3"86;
"CKE"
$PN"K2"25;
"ZQ"
$PN"F9"37;
"VREFCA"
$PN"M1"36;
"RAS#/A16 \B"
$PN"L8"94;
"CAS#/A15 \B"
$PN"M8"95;
"WE#/A14 \B"
$PN"L2"96;
"A13"
$PN"T8"105;
"A12/BC# \B"
$PN"M7"97;
"A11"
$PN"T2"112;
"A10/AP"
$PN"M3"98;
"A9"
$PN"R7"107;
"A8"
$PN"R2"99;
"A7"
$PN"R8"106;
"A6"
$PN"P2"100;
"A5"
$PN"P8"104;
"A4"
$PN"N3"73;
"A3"
$PN"N7"74;
"A2"
$PN"R3"101;
"A1"
$PN"P7"103;
"A0"
$PN"P3"102;
"DQL7"
$PN"J7"80;
"DQL6"
$PN"J3"47;
"DQL5"
$PN"H8"79;
"DQL3"
$PN"H7"78;
"DQL2"
$PN"H3"49;
"DQL4"
$PN"H2"48;
"DQL0"
$PN"G2"50;
"DQL1"
$PN"F7"77;
"DQU3"
$PN"C7"24;
"DQU2"
$PN"C3"52;
"DQU1"
$PN"B8"53;
"DQU0"
$PN"A3"54;
"DQU7"
$PN"D7"51;
"DQU6"
$PN"D3"84;
"DQU5"
$PN"C8"83;
"DQU4"
$PN"C2"72;
"VDDQ<9>"
$PN"J8"20;
"VDDQ<8>"
$PN"J2"20;
"VDDQ<7>"
$PN"G9"20;
"VDDQ<6>"
$PN"G1"20;
"VDDQ<5>"
$PN"F8"20;
"VDDQ<4>"
$PN"F2"20;
"VDDQ<3>"
$PN"D9"20;
"VDDQ<2>"
$PN"C1"20;
"VDDQ<1>"
$PN"A9"20;
"VDDQ<0>"
$PN"A1"20;
"VDD<9>"
$PN"T9"20;
"VDD<8>"
$PN"R1"20;
"VDD<7>"
$PN"L9"20;
"VDD<6>"
$PN"L1"20;
"VDD<5>"
$PN"J9"20;
"VDD<4>"
$PN"J1"20;
"VDD<3>"
$PN"G7"20;
"VDD<2>"
$PN"D1"20;
"VDD<1>"
$PN"B9"20;
"VDD<0>"
$PN"B3"20;
"VPP<0>"
$PN"B1"21;
%"W_VCC_CIRCLE"
"1","(50,1825)","0","w_power","I51";
;
HDL_POWER"P1V2_AUX_BMC"
BODY_TYPE"PLUMBING"
CDS_LMAN_SYM_OUTLINE"-100,100,100,-100"
CDS_LIB"w_power";
"VCC_CIRCLE \B"17;
%"W_VCC_CIRCLE"
"1","(2775,2300)","0","w_power","I54";
;
HDL_POWER"P1V2_AUX_BMC"
BODY_TYPE"PLUMBING"
CDS_LMAN_SYM_OUTLINE"-100,100,100,-100"
CDS_LIB"w_power";
"VCC_CIRCLE \B"18;
%"RES"
"2","(2775,2150)","0","mstr_discrete","I55";
;
VALUE"4.75K"
POP"NOPOP"
MATERIAL"CHIP"
PACK_TYPE"0402"
WATTAGE"1/16W"
TOLERANCE"1%"
LOCATION"R9F29"
PART_NUMBER"G21796-072"
CDS_SEC"1"
ROOM"BMC_MEMORY"
CDS_LOCATION"R9F29"
SEC"1"
BOM_COST"SM_MEM"
CDS_LIB"mstr_discrete"
SEC_TYPE"0402";
"A"
$PN"1"18;
"B"
$PN"2"27;
%"TTL1G07_A"
"1","(2025,1975)","0","mstr_ttl","I56";
;
POP"NOPOP"
VALUE"74LVC1G07"
PART_NUMBER"C88419-001"
POWER_GROUP"VCC=P3V3_STBY;GND=GND"
LOCATION"U9F3"
MATERIAL"IC"
PACK_TYPE"SOP"
CDS_LIB"mstr_ttl"
SEC_TYPE"SOP"
SEC"1"
CDS_LOCATION"U9F3"
ROOM"BMC_MEMORY"
CDS_SEC"1";
"Y"
$PN"4"27;
"A"
$PN"2"90;
%"CAP"
"1","(-2075,2100)","0","mstr_discrete","I58";
;
CDS_SEC"1"
PACK_TYPE"0402LF"
VOLTAGE"50V"
TOLERANCE"5%"
VALUE"100.0PF"
PART_NUMBER"A36095-026"
LOCATION"C25W16"
MATERIAL"COG"
CDS_LIB"mstr_discrete"
ROOM"BMC"
BOM_COST"SM_CONTROLLER"
CDS_LOCATION"C25W16"
SEC"1"
SEC_TYPE"0402LF";
"A"
$PN"1"3;
"B"
$PN"2"4;
%"GND"
"1","(3350,-1550)","0","mstr_symbols","I85";
;
HDL_POWER"GND"
BODY_TYPE"PLUMBING"
VOLTAGE"0.0V"
SIZE"1B"
CDS_LIB"mstr_symbols";
"A\NAC"19;
%"W_VCC_CIRCLE"
"1","(1900,1500)","0","w_power","I86";
;
HDL_POWER"P1V2_AUX_BMC"
BODY_TYPE"PLUMBING"
CDS_LMAN_SYM_OUTLINE"-100,100,100,-100"
CDS_LIB"w_power";
"VCC_CIRCLE \B"20;
%"W_VCC_CIRCLE"
"1","(1100,750)","0","w_power","I88";
;
HDL_POWER"P2V5_AUX_BMC"
BODY_TYPE"PLUMBING"
CDS_LMAN_SYM_OUTLINE"-100,100,100,-100"
CDS_LIB"w_power";
"VCC_CIRCLE \B"21;
%"GND"
"1","(1100,200)","0","mstr_symbols","I91";
;
HDL_POWER"GND"
BODY_TYPE"PLUMBING"
SIZE"1B"
CDS_LIB"mstr_symbols"
VOLTAGE"0.0V";
"A\NAC"22;
END.
